# Barreleye-G2_Tri-mode BPX24-DVT-X01-SKU-BOM-X07-20171222_Final.xls.xlsx — Summary (bom)
| PLATFORM SOURCING AND PSL COMPLIANCE |  |  |  |  |  |  |  |  |  |
| Platform Name: |  |  |  |  |  |  |  |  |  |
| REVISION HISTORY |  |  |  |  |  |  |  |  |  |
| BOM Revision: | ECR # | Revision Description | Originator | Date |  |  |  |  |  |
| X03 |  | EVT |  | 42891 |  |  |  |  |  |
| X07 |  |  |  | 43091 |  |  |  |  |  |
| Commodity Sourcing | # of components (X00 BOM) | % of Total | # of components (X01 BOM) | % of Total | # of components (X02 BOM) | % of Total | # of components (RTS) | % of Total | Risk Mitigation Plans in Place |
| Sole Source |  |  |  |  |  |  |  |  |  |
| Single Source |  |  | 15 | 0.141509434 |  |  |  |  |  |
| Multiple |  |  | 91 | 0.858490566 |  |  |  |  | NA |
| Total |  |  | 106 | 1 |  |  |  |  | NA |
|  |  | # of components | # of components aligned with Customer PSL* | % PSL alignment |  |  |  |  |  |
| Class 1 (Customer Managed) |  |  |  |  |  |  |  |  |  |
| Class 2 (ODM Managed to Customer PSL) |  |  |  |  |  |  |  |  |  |
| All other components(ODM Managed to ODM PSL) |  |  |  |  |  |  |  |  |  |
| *RFQ and/or Contract will list requirements for complying with Customer's PSL |  |  |  |  |  |  |  |  |  |
| Reference for quotation |  |  |  |  |  |  |  |  |  |
